(kicad_pcb
	(version 20260206)
	(generator "pcbnew")
	(generator_version "10.0")
	(general
		(thickness 1.6)
		(legacy_teardrops no)
	)
	(paper "A4")
	(title_block
		(title "03242023_DA0F0TMBIJ0_F0T_Motherboard_J_brd_V01_OCP.brd")
		(comment 1 "Grand Teton / footprint 501 of 6105 (J22), pads 1-112 of 291")
	)
	(layers
		(0 "F.Cu" signal "TOP")
		(4 "In1.Cu" signal "GND")
		(6 "In2.Cu" signal "IN1")
		(8 "In3.Cu" signal "GND1")
		(10 "In4.Cu" signal "IN2")
		(12 "In5.Cu" signal "GND2")
		(14 "In6.Cu" signal "IN3")
		(16 "In7.Cu" signal "GND3")
		(18 "In8.Cu" signal "VCC")
		(20 "In9.Cu" signal "VCC1")
		(22 "In10.Cu" signal "GND4")
		(24 "In11.Cu" signal "IN4")
		(26 "In12.Cu" signal "GND5")
		(28 "In13.Cu" signal "IN5")
		(30 "In14.Cu" signal "GND6")
		(32 "In15.Cu" signal "IN6")
		(34 "In16.Cu" signal "GND7")
		(2 "B.Cu" signal "BOTTOM")
		(9 "F.Adhes" user "F.Adhesive")
		(11 "B.Adhes" user "B.Adhesive")
		(13 "F.Paste" user "Package Geometry/Pastemask Top")
		(15 "B.Paste" user "Package Geometry/Pastemask Bottom")
		(5 "F.SilkS" user "Ref Des/Silkscreen Top")
		(7 "B.SilkS" user "Ref Des/Silkscreen Bottom")
		(1 "F.Mask" user "Board Geometry/Soldermask Top")
		(3 "B.Mask" user "Board Geometry/Soldermask Bottom")
		(17 "Dwgs.User" user "User.Drawings")
		(19 "Cmts.User" user "User.Comments")
		(21 "Eco1.User" user "User.Eco1")
		(23 "Eco2.User" user "User.Eco2")
		(25 "Edge.Cuts" user "Board Geometry/Outline")
		(27 "Margin" user)
		(31 "F.CrtYd" user "Package Geometry/Place Bound Top")
		(29 "B.CrtYd" user "Package Geometry/Place Bound Bottom")
		(35 "F.Fab" user "Ref Des/Assembly Top")
		(33 "B.Fab" user "Ref Des/Assembly Bottom")
	)
	(footprint ""
		(layer "F.Cu")
		(at 32.82188 -258.091686)
		(property "Reference" "J22"
			(at -1.420622 -81.912714 0)
			(unlocked yes)
			(layer "F.SilkS")
			(effects
				(font
					(size 0.7874 0.5842)
					(thickness 0.1524)
				)
				(justify left)
			)
		)
		(property "Value" ""
			(at 0 0 0)
			(layer "F.Fab")
			(effects
				(font
					(size 1.27 1.27)
				)
			)
		)
		(duplicate_pad_numbers_are_jumpers no)
		(pad "1" smd rect
			(at -2.050034 -63.324994 270)
			(size 0.519938 1.4986)
			(layers "F.Cu" "F.Mask" "F.Paste")
			(net "P12V_S3_AUX_CPU1_NVDIMM")
		)
		(pad "2" smd rect
			(at -2.050034 -62.47511 270)
			(size 0.519938 1.4986)
			(layers "F.Cu" "F.Mask" "F.Paste")
			(net "TP_CHC_CPU1_DIMM2_FRU_0")
		)
		(pad "3" smd rect
			(at -2.050034 -61.624972 270)
			(size 0.519938 1.4986)
			(layers "F.Cu" "F.Mask" "F.Paste")
			(net "P3V3_AUX")
		)
		(pad "4" smd rect
			(at -2.050034 -60.775088 270)
			(size 0.519938 1.4986)
			(layers "F.Cu" "F.Mask" "F.Paste")
			(net "I3C_SPD_DDRABCD_CPU1_LVC1_SCL_5")
		)
		(pad "5" smd rect
			(at -2.050034 -59.92495 270)
			(size 0.519938 1.4986)
			(layers "F.Cu" "F.Mask" "F.Paste")
			(net "I3C_SPD_DDRABCD_CPU1_LVC1_SDA")
		)
		(pad "6" smd rect
			(at -2.050034 -59.075066 270)
			(size 0.519938 1.4986)
			(layers "F.Cu" "F.Mask" "F.Paste")
			(net "GND")
		)
		(pad "7" smd rect
			(at -2.050034 -58.224928 270)
			(size 0.519938 1.4986)
			(layers "F.Cu" "F.Mask" "F.Paste")
			(net "M_C_CPU1_SA_DQ<0>")
		)
		(pad "8" smd rect
			(at -2.050034 -57.375044 270)
			(size 0.519938 1.4986)
			(layers "F.Cu" "F.Mask" "F.Paste")
			(net "GND")
		)
		(pad "9" smd rect
			(at -2.050034 -56.524906 270)
			(size 0.519938 1.4986)
			(layers "F.Cu" "F.Mask" "F.Paste")
			(net "M_C_CPU1_SA_DQ<1>")
		)
		(pad "10" smd rect
			(at -2.050034 -55.675022 270)
			(size 0.519938 1.4986)
			(layers "F.Cu" "F.Mask" "F.Paste")
			(net "GND")
		)
		(pad "11" smd rect
			(at -2.050034 -54.824884 270)
			(size 0.519938 1.4986)
			(layers "F.Cu" "F.Mask" "F.Paste")
			(net "M_C_CPU1_SA_DQS_DP<0>")
		)
		(pad "12" smd rect
			(at -2.050034 -53.975 270)
			(size 0.519938 1.4986)
			(layers "F.Cu" "F.Mask" "F.Paste")
			(net "M_C_CPU1_SA_DQS_DN<0>")
		)
		(pad "13" smd rect
			(at -2.050034 -53.125116 270)
			(size 0.519938 1.4986)
			(layers "F.Cu" "F.Mask" "F.Paste")
			(net "GND")
		)
		(pad "14" smd rect
			(at -2.050034 -52.274978 270)
			(size 0.519938 1.4986)
			(layers "F.Cu" "F.Mask" "F.Paste")
			(net "M_C_CPU1_SA_DQ<4>")
		)
		(pad "15" smd rect
			(at -2.050034 -51.425094 270)
			(size 0.519938 1.4986)
			(layers "F.Cu" "F.Mask" "F.Paste")
			(net "GND")
		)
		(pad "16" smd rect
			(at -2.050034 -50.574956 270)
			(size 0.519938 1.4986)
			(layers "F.Cu" "F.Mask" "F.Paste")
			(net "M_C_CPU1_SA_DQ<5>")
		)
		(pad "17" smd rect
			(at -2.050034 -49.725072 270)
			(size 0.519938 1.4986)
			(layers "F.Cu" "F.Mask" "F.Paste")
			(net "GND")
		)
		(pad "18" smd rect
			(at -2.050034 -48.874934 270)
			(size 0.519938 1.4986)
			(layers "F.Cu" "F.Mask" "F.Paste")
			(net "M_C_CPU1_SA_DQ<8>")
		)
		(pad "19" smd rect
			(at -2.050034 -48.02505 270)
			(size 0.519938 1.4986)
			(layers "F.Cu" "F.Mask" "F.Paste")
			(net "GND")
		)
		(pad "20" smd rect
			(at -2.050034 -47.174912 270)
			(size 0.519938 1.4986)
			(layers "F.Cu" "F.Mask" "F.Paste")
			(net "M_C_CPU1_SA_DQ<9>")
		)
		(pad "21" smd rect
			(at -2.050034 -46.325028 270)
			(size 0.519938 1.4986)
			(layers "F.Cu" "F.Mask" "F.Paste")
			(net "GND")
		)
		(pad "22" smd rect
			(at -2.050034 -45.47489 270)
			(size 0.519938 1.4986)
			(layers "F.Cu" "F.Mask" "F.Paste")
			(net "M_C_CPU1_SA_DQS_DP<1>")
		)
		(pad "23" smd rect
			(at -2.050034 -44.625006 270)
			(size 0.519938 1.4986)
			(layers "F.Cu" "F.Mask" "F.Paste")
			(net "M_C_CPU1_SA_DQS_DN<1>")
		)
		(pad "24" smd rect
			(at -2.050034 -43.775122 270)
			(size 0.519938 1.4986)
			(layers "F.Cu" "F.Mask" "F.Paste")
			(net "GND")
		)
		(pad "25" smd rect
			(at -2.050034 -42.924984 270)
			(size 0.519938 1.4986)
			(layers "F.Cu" "F.Mask" "F.Paste")
			(net "M_C_CPU1_SA_DQ<12>")
		)
		(pad "26" smd rect
			(at -2.050034 -42.0751 270)
			(size 0.519938 1.4986)
			(layers "F.Cu" "F.Mask" "F.Paste")
			(net "GND")
		)
		(pad "27" smd rect
			(at -2.050034 -41.224962 270)
			(size 0.519938 1.4986)
			(layers "F.Cu" "F.Mask" "F.Paste")
			(net "M_C_CPU1_SA_DQ<13>")
		)
		(pad "28" smd rect
			(at -2.050034 -40.375078 270)
			(size 0.519938 1.4986)
			(layers "F.Cu" "F.Mask" "F.Paste")
			(net "GND")
		)
		(pad "29" smd rect
			(at -2.050034 -39.52494 270)
			(size 0.519938 1.4986)
			(layers "F.Cu" "F.Mask" "F.Paste")
			(net "M_C_CPU1_SA_DQ<16>")
		)
		(pad "30" smd rect
			(at -2.050034 -38.675056 270)
			(size 0.519938 1.4986)
			(layers "F.Cu" "F.Mask" "F.Paste")
			(net "GND")
		)
		(pad "31" smd rect
			(at -2.050034 -37.824918 270)
			(size 0.519938 1.4986)
			(layers "F.Cu" "F.Mask" "F.Paste")
			(net "M_C_CPU1_SA_DQ<17>")
		)
		(pad "32" smd rect
			(at -2.050034 -36.975034 270)
			(size 0.519938 1.4986)
			(layers "F.Cu" "F.Mask" "F.Paste")
			(net "GND")
		)
		(pad "33" smd rect
			(at -2.050034 -36.124896 270)
			(size 0.519938 1.4986)
			(layers "F.Cu" "F.Mask" "F.Paste")
			(net "M_C_CPU1_SA_DQS_DP<2>")
		)
		(pad "34" smd rect
			(at -2.050034 -35.275012 270)
			(size 0.519938 1.4986)
			(layers "F.Cu" "F.Mask" "F.Paste")
			(net "M_C_CPU1_SA_DQS_DN<2>")
		)
		(pad "35" smd rect
			(at -2.050034 -34.425128 270)
			(size 0.519938 1.4986)
			(layers "F.Cu" "F.Mask" "F.Paste")
			(net "GND")
		)
		(pad "36" smd rect
			(at -2.050034 -33.57499 270)
			(size 0.519938 1.4986)
			(layers "F.Cu" "F.Mask" "F.Paste")
			(net "M_C_CPU1_SA_DQ<20>")
		)
		(pad "37" smd rect
			(at -2.050034 -32.725106 270)
			(size 0.519938 1.4986)
			(layers "F.Cu" "F.Mask" "F.Paste")
			(net "GND")
		)
		(pad "38" smd rect
			(at -2.050034 -31.874968 270)
			(size 0.519938 1.4986)
			(layers "F.Cu" "F.Mask" "F.Paste")
			(net "M_C_CPU1_SA_DQ<21>")
		)
		(pad "39" smd rect
			(at -2.050034 -31.025084 270)
			(size 0.519938 1.4986)
			(layers "F.Cu" "F.Mask" "F.Paste")
			(net "GND")
		)
		(pad "40" smd rect
			(at -2.050034 -30.174946 270)
			(size 0.519938 1.4986)
			(layers "F.Cu" "F.Mask" "F.Paste")
			(net "M_C_CPU1_SA_DQ<24>")
		)
		(pad "41" smd rect
			(at -2.050034 -29.325062 270)
			(size 0.519938 1.4986)
			(layers "F.Cu" "F.Mask" "F.Paste")
			(net "GND")
		)
		(pad "42" smd rect
			(at -2.050034 -28.474924 270)
			(size 0.519938 1.4986)
			(layers "F.Cu" "F.Mask" "F.Paste")
			(net "M_C_CPU1_SA_DQ<25>")
		)
		(pad "43" smd rect
			(at -2.050034 -27.62504 270)
			(size 0.519938 1.4986)
			(layers "F.Cu" "F.Mask" "F.Paste")
			(net "GND")
		)
		(pad "44" smd rect
			(at -2.050034 -26.774902 270)
			(size 0.519938 1.4986)
			(layers "F.Cu" "F.Mask" "F.Paste")
			(net "M_C_CPU1_SA_DQS_DP<3>")
		)
		(pad "45" smd rect
			(at -2.050034 -25.925018 270)
			(size 0.519938 1.4986)
			(layers "F.Cu" "F.Mask" "F.Paste")
			(net "M_C_CPU1_SA_DQS_DN<3>")
		)
		(pad "46" smd rect
			(at -2.050034 -25.07488 270)
			(size 0.519938 1.4986)
			(layers "F.Cu" "F.Mask" "F.Paste")
			(net "GND")
		)
		(pad "47" smd rect
			(at -2.050034 -24.224996 270)
			(size 0.519938 1.4986)
			(layers "F.Cu" "F.Mask" "F.Paste")
			(net "M_C_CPU1_SA_DQ<28>")
		)
		(pad "48" smd rect
			(at -2.050034 -23.375112 270)
			(size 0.519938 1.4986)
			(layers "F.Cu" "F.Mask" "F.Paste")
			(net "GND")
		)
		(pad "49" smd rect
			(at -2.050034 -22.524974 270)
			(size 0.519938 1.4986)
			(layers "F.Cu" "F.Mask" "F.Paste")
			(net "M_C_CPU1_SA_DQ<29>")
		)
		(pad "50" smd rect
			(at -2.050034 -21.67509 270)
			(size 0.519938 1.4986)
			(layers "F.Cu" "F.Mask" "F.Paste")
			(net "GND")
		)
		(pad "51" smd rect
			(at -2.050034 -20.824952 270)
			(size 0.519938 1.4986)
			(layers "F.Cu" "F.Mask" "F.Paste")
			(net "M_C_CPU1_SA_CB<0>")
		)
		(pad "52" smd rect
			(at -2.050034 -19.975068 270)
			(size 0.519938 1.4986)
			(layers "F.Cu" "F.Mask" "F.Paste")
			(net "GND")
		)
		(pad "53" smd rect
			(at -2.050034 -19.12493 270)
			(size 0.519938 1.4986)
			(layers "F.Cu" "F.Mask" "F.Paste")
			(net "M_C_CPU1_SA_CB<1>")
		)
		(pad "54" smd rect
			(at -2.050034 -18.275046 270)
			(size 0.519938 1.4986)
			(layers "F.Cu" "F.Mask" "F.Paste")
			(net "GND")
		)
		(pad "55" smd rect
			(at -2.050034 -17.424908 270)
			(size 0.519938 1.4986)
			(layers "F.Cu" "F.Mask" "F.Paste")
			(net "M_C_CPU1_SA_DQS_DP<4>")
		)
		(pad "56" smd rect
			(at -2.050034 -16.575024 270)
			(size 0.519938 1.4986)
			(layers "F.Cu" "F.Mask" "F.Paste")
			(net "M_C_CPU1_SA_DQS_DN<4>")
		)
		(pad "57" smd rect
			(at -2.050034 -15.724886 270)
			(size 0.519938 1.4986)
			(layers "F.Cu" "F.Mask" "F.Paste")
			(net "GND")
		)
		(pad "58" smd rect
			(at -2.050034 -14.875002 270)
			(size 0.519938 1.4986)
			(layers "F.Cu" "F.Mask" "F.Paste")
			(net "M_C_CPU1_SA_CB<4>")
		)
		(pad "59" smd rect
			(at -2.050034 -14.025118 270)
			(size 0.519938 1.4986)
			(layers "F.Cu" "F.Mask" "F.Paste")
			(net "GND")
		)
		(pad "60" smd rect
			(at -2.050034 -13.17498 270)
			(size 0.519938 1.4986)
			(layers "F.Cu" "F.Mask" "F.Paste")
			(net "M_C_CPU1_SA_CB<5>")
		)
		(pad "61" smd rect
			(at -2.050034 -12.325096 270)
			(size 0.519938 1.4986)
			(layers "F.Cu" "F.Mask" "F.Paste")
			(net "GND")
		)
		(pad "62" smd rect
			(at -2.050034 -11.474958 270)
			(size 0.519938 1.4986)
			(layers "F.Cu" "F.Mask" "F.Paste")
			(net "M_C_CPU1_ALERT_N")
		)
		(pad "63" smd rect
			(at -2.050034 -10.625074 270)
			(size 0.519938 1.4986)
			(layers "F.Cu" "F.Mask" "F.Paste")
			(net "GND")
		)
		(pad "64" smd rect
			(at -2.050034 -9.774936 270)
			(size 0.519938 1.4986)
			(layers "F.Cu" "F.Mask" "F.Paste")
			(net "M_C_CPU1_SA_CS_N<2>")
		)
		(pad "65" smd rect
			(at -2.050034 -8.925052 270)
			(size 0.519938 1.4986)
			(layers "F.Cu" "F.Mask" "F.Paste")
			(net "GND")
		)
		(pad "66" smd rect
			(at -2.050034 -8.074914 270)
			(size 0.519938 1.4986)
			(layers "F.Cu" "F.Mask" "F.Paste")
			(net "M_C_CPU1_SA_CA<0>")
		)
		(pad "67" smd rect
			(at -2.050034 -7.22503 270)
			(size 0.519938 1.4986)
			(layers "F.Cu" "F.Mask" "F.Paste")
			(net "GND")
		)
		(pad "68" smd rect
			(at -2.050034 -6.374892 270)
			(size 0.519938 1.4986)
			(layers "F.Cu" "F.Mask" "F.Paste")
			(net "M_C_CPU1_SA_CA<2>")
		)
		(pad "69" smd rect
			(at -2.050034 -5.525008 270)
			(size 0.519938 1.4986)
			(layers "F.Cu" "F.Mask" "F.Paste")
			(net "GND")
		)
		(pad "70" smd rect
			(at -2.050034 -4.675124 270)
			(size 0.519938 1.4986)
			(layers "F.Cu" "F.Mask" "F.Paste")
			(net "M_C_CPU1_SA_CA<4>")
		)
		(pad "71" smd rect
			(at -2.050034 -3.824986 270)
			(size 0.519938 1.4986)
			(layers "F.Cu" "F.Mask" "F.Paste")
			(net "GND")
		)
		(pad "72" smd rect
			(at -2.050034 -2.975102 270)
			(size 0.519938 1.4986)
			(layers "F.Cu" "F.Mask" "F.Paste")
			(net "M_C_CPU1_SA_CA<6>")
		)
		(pad "73" smd rect
			(at -2.050034 -2.124964 270)
			(size 0.519938 1.4986)
			(layers "F.Cu" "F.Mask" "F.Paste")
			(net "GND")
		)
		(pad "74" smd rect
			(at -2.050034 -1.27508 270)
			(size 0.519938 1.4986)
			(layers "F.Cu" "F.Mask" "F.Paste")
			(net "M_C_CPU1_SA_PAR")
		)
		(pad "75" smd rect
			(at -2.050034 -0.424942 270)
			(size 0.519938 1.4986)
			(layers "F.Cu" "F.Mask" "F.Paste")
			(net "GND")
		)
		(pad "76" smd rect
			(at -2.050034 5.525008 270)
			(size 0.519938 1.4986)
			(layers "F.Cu" "F.Mask" "F.Paste")
			(net "M_C_CPU1_SB_CA<0>")
		)
		(pad "77" smd rect
			(at -2.050034 6.374892 270)
			(size 0.519938 1.4986)
			(layers "F.Cu" "F.Mask" "F.Paste")
			(net "GND")
		)
		(pad "78" smd rect
			(at -2.050034 7.22503 270)
			(size 0.519938 1.4986)
			(layers "F.Cu" "F.Mask" "F.Paste")
			(net "M_C_CPU1_SB_CA<2>")
		)
		(pad "79" smd rect
			(at -2.050034 8.074914 270)
			(size 0.519938 1.4986)
			(layers "F.Cu" "F.Mask" "F.Paste")
			(net "GND")
		)
		(pad "80" smd rect
			(at -2.050034 8.925052 270)
			(size 0.519938 1.4986)
			(layers "F.Cu" "F.Mask" "F.Paste")
			(net "M_C_CPU1_SB_CA<4>")
		)
		(pad "81" smd rect
			(at -2.050034 9.774936 270)
			(size 0.519938 1.4986)
			(layers "F.Cu" "F.Mask" "F.Paste")
			(net "GND")
		)
		(pad "82" smd rect
			(at -2.050034 10.625074 270)
			(size 0.519938 1.4986)
			(layers "F.Cu" "F.Mask" "F.Paste")
			(net "M_C_CPU1_SB_CA<6>")
		)
		(pad "83" smd rect
			(at -2.050034 11.474958 270)
			(size 0.519938 1.4986)
			(layers "F.Cu" "F.Mask" "F.Paste")
			(net "GND")
		)
		(pad "84" smd rect
			(at -2.050034 12.325096 270)
			(size 0.519938 1.4986)
			(layers "F.Cu" "F.Mask" "F.Paste")
			(net "M_C_CPU1_SB_CS_N<2>")
		)
		(pad "85" smd rect
			(at -2.050034 13.17498 270)
			(size 0.519938 1.4986)
			(layers "F.Cu" "F.Mask" "F.Paste")
			(net "GND")
		)
		(pad "86" smd rect
			(at -2.050034 14.025118 270)
			(size 0.519938 1.4986)
			(layers "F.Cu" "F.Mask" "F.Paste")
			(net "M_C_CPU1_SA_RSP<1>")
		)
		(pad "87" smd rect
			(at -2.050034 14.875002 270)
			(size 0.519938 1.4986)
			(layers "F.Cu" "F.Mask" "F.Paste")
			(net "M_C_CPU1_SB_RSP<1>")
		)
		(pad "88" smd rect
			(at -2.050034 15.724886 270)
			(size 0.519938 1.4986)
			(layers "F.Cu" "F.Mask" "F.Paste")
			(net "GND")
		)
		(pad "89" smd rect
			(at -2.050034 16.575024 270)
			(size 0.519938 1.4986)
			(layers "F.Cu" "F.Mask" "F.Paste")
			(net "M_C_CPU1_SB_CB<4>")
		)
		(pad "90" smd rect
			(at -2.050034 17.424908 270)
			(size 0.519938 1.4986)
			(layers "F.Cu" "F.Mask" "F.Paste")
			(net "GND")
		)
		(pad "91" smd rect
			(at -2.050034 18.275046 270)
			(size 0.519938 1.4986)
			(layers "F.Cu" "F.Mask" "F.Paste")
			(net "M_C_CPU1_SB_CB<5>")
		)
		(pad "92" smd rect
			(at -2.050034 19.12493 270)
			(size 0.519938 1.4986)
			(layers "F.Cu" "F.Mask" "F.Paste")
			(net "GND")
		)
		(pad "93" smd rect
			(at -2.050034 19.975068 270)
			(size 0.519938 1.4986)
			(layers "F.Cu" "F.Mask" "F.Paste")
			(net "M_C_CPU1_SB_DQS_DP<9>")
		)
		(pad "94" smd rect
			(at -2.050034 20.824952 270)
			(size 0.519938 1.4986)
			(layers "F.Cu" "F.Mask" "F.Paste")
			(net "M_C_CPU1_SB_DQS_DN<9>")
		)
		(pad "95" smd rect
			(at -2.050034 21.67509 270)
			(size 0.519938 1.4986)
			(layers "F.Cu" "F.Mask" "F.Paste")
			(net "GND")
		)
		(pad "96" smd rect
			(at -2.050034 22.524974 270)
			(size 0.519938 1.4986)
			(layers "F.Cu" "F.Mask" "F.Paste")
			(net "M_C_CPU1_SB_CB<0>")
		)
		(pad "97" smd rect
			(at -2.050034 23.375112 270)
			(size 0.519938 1.4986)
			(layers "F.Cu" "F.Mask" "F.Paste")
			(net "GND")
		)
		(pad "98" smd rect
			(at -2.050034 24.224996 270)
			(size 0.519938 1.4986)
			(layers "F.Cu" "F.Mask" "F.Paste")
			(net "M_C_CPU1_SB_CB<1>")
		)
		(pad "99" smd rect
			(at -2.050034 25.07488 270)
			(size 0.519938 1.4986)
			(layers "F.Cu" "F.Mask" "F.Paste")
			(net "GND")
		)
		(pad "100" smd rect
			(at -2.050034 25.925018 270)
			(size 0.519938 1.4986)
			(layers "F.Cu" "F.Mask" "F.Paste")
			(net "M_C_CPU1_SB_DQ<0>")
		)
		(pad "101" smd rect
			(at -2.050034 26.774902 270)
			(size 0.519938 1.4986)
			(layers "F.Cu" "F.Mask" "F.Paste")
			(net "GND")
		)
		(pad "102" smd rect
			(at -2.050034 27.62504 270)
			(size 0.519938 1.4986)
			(layers "F.Cu" "F.Mask" "F.Paste")
			(net "M_C_CPU1_SB_DQ<1>")
		)
		(pad "103" smd rect
			(at -2.050034 28.474924 270)
			(size 0.519938 1.4986)
			(layers "F.Cu" "F.Mask" "F.Paste")
			(net "GND")
		)
		(pad "104" smd rect
			(at -2.050034 29.325062 270)
			(size 0.519938 1.4986)
			(layers "F.Cu" "F.Mask" "F.Paste")
			(net "M_C_CPU1_SB_DQS_DP<0>")
		)
		(pad "105" smd rect
			(at -2.050034 30.174946 270)
			(size 0.519938 1.4986)
			(layers "F.Cu" "F.Mask" "F.Paste")
			(net "M_C_CPU1_SB_DQS_DN<0>")
		)
		(pad "106" smd rect
			(at -2.050034 31.025084 270)
			(size 0.519938 1.4986)
			(layers "F.Cu" "F.Mask" "F.Paste")
			(net "GND")
		)
		(pad "107" smd rect
			(at -2.050034 31.874968 270)
			(size 0.519938 1.4986)
			(layers "F.Cu" "F.Mask" "F.Paste")
			(net "M_C_CPU1_SB_DQ<4>")
		)
		(pad "108" smd rect
			(at -2.050034 32.725106 270)
			(size 0.519938 1.4986)
			(layers "F.Cu" "F.Mask" "F.Paste")
			(net "GND")
		)
		(pad "109" smd rect
			(at -2.050034 33.57499 270)
			(size 0.519938 1.4986)
			(layers "F.Cu" "F.Mask" "F.Paste")
			(net "M_C_CPU1_SB_DQ<5>")
		)
		(pad "110" smd rect
			(at -2.050034 34.425128 270)
			(size 0.519938 1.4986)
			(layers "F.Cu" "F.Mask" "F.Paste")
			(net "GND")
		)
		(pad "111" smd rect
			(at -2.050034 35.275012 270)
			(size 0.519938 1.4986)
			(layers "F.Cu" "F.Mask" "F.Paste")
			(net "M_C_CPU1_SB_DQ<8>")
		)
		(pad "112" smd rect
			(at -2.050034 36.124896 270)
			(size 0.519938 1.4986)
			(layers "F.Cu" "F.Mask" "F.Paste")
			(net "GND")
		)
	)
)
